# TIMECARD (Time Appliance Project (Time Card)) — schematic netlist excerpt (pin names and nets, part order shuffled) for the footprints in the layout excerpt that follows; sources: Cadence DE-HDL packaged netlist, KiCad conversion of R4006-B0001-02_R01.brd

U29  BNO080_LGA_28  BNO085  pkg LGA28_205X150_P0197  page 20
  RESV_NC_1  = NC
  GND_1  = SG
  VDD  = VDD_BNO085
  BOOTN  = R_BNO080_BOOT_N
  PS1  = UNNAMED_9_BNO080LGA28_I29_PS1
  \ps0/wake\  = UNNAMED_9_BNO080LGA28_I29_PS0
  RESV_NC_2  = NC
  RESV_NC_3  = NC
  CAP  = UNNAMED_9_BNO080LGA28_I29_CAP
  CLKSEL0  = UNNAMED_9_BNO080LGA28_I29_CLKSE
  \rst*\  = R_BNO080_RST_N
  RESV_NC_4  = NC
  RESV_NC_5  = NC
  H_INTN  = R_BNO080_INT_N
  ENV_SCL  = R_BNO080_EVN_SCL
  ENV_SDA  = R_BNO080_EVN_SDA
  \sa0/h_mosi\  = BNO080_SA0
  \h_cs*\  = UNNAMED_9_BNO080LGA28_I29_HCS
  \h_scl/sck/rx\  = R_BNO080_I2C_SCL
  \h_sda/h_miso/tx\  = R_BNO080_I2C_SDA
  RESV_NC_6  = NC
  RESV_NC_7  = NC
  RESV_NC_8  = NC
  RESV_NC_9  = NC
  GND_2  = SG
  \xout32/clksel1\  = UNNAMED_9_BNO080LGA28_I29_XOUT3
  XIN32  = UNNAMED_9_CAPACITOR_I17_1
  VDDIO  = VDD_BNO085

(kicad_pcb
	(version 20260206)
	(generator "pcbnew")
	(generator_version "10.0")
	(general
		(thickness 1.6)
		(legacy_teardrops no)
	)
	(paper "A4")
	(title_block
		(title "timecard-production-celestica-r4006 — R4006-B0001-02_R01.brd")
		(comment 1 "Time Appliance Project (Time Card) / footprint 103 of 1113 (U29), pads 1-28 of 28")
	)
	(layers
		(0 "F.Cu" signal "TOP")
		(4 "In1.Cu" signal "L02_GND1")
		(6 "In2.Cu" signal "L03_SIG1")
		(8 "In3.Cu" signal "L04_GND2")
		(10 "In4.Cu" signal "L05_VCC1")
		(12 "In5.Cu" signal "L06_VCC2")
		(14 "In6.Cu" signal "L07_GND3")
		(16 "In7.Cu" signal "L08_SIG2")
		(18 "In8.Cu" signal "L09_GND4")
		(2 "B.Cu" signal "BOTTOM")
		(9 "F.Adhes" user "F.Adhesive")
		(11 "B.Adhes" user "B.Adhesive")
		(13 "F.Paste" user "Package Geometry/Pastemask Top")
		(15 "B.Paste" user "Package Geometry/Pastemask Bottom")
		(5 "F.SilkS" user "Ref Des/Silkscreen Top")
		(7 "B.SilkS" user "Ref Des/Silkscreen Bottom")
		(1 "F.Mask" user "Board Geometry/Soldermask Top")
		(3 "B.Mask" user "Board Geometry/Soldermask Bottom")
		(17 "Dwgs.User" user "User.Drawings")
		(19 "Cmts.User" user "User.Comments")
		(21 "Eco1.User" user "User.Eco1")
		(23 "Eco2.User" user "User.Eco2")
		(25 "Edge.Cuts" user "Board Geometry/Outline")
		(27 "Margin" user)
		(31 "F.CrtYd" user "Package Geometry/Place Bound Top")
		(29 "B.CrtYd" user "Package Geometry/Place Bound Bottom")
		(35 "F.Fab" user "Ref Des/Assembly Top")
		(33 "B.Fab" user "Ref Des/Assembly Bottom")
	)
	(footprint ""
		(layer "F.Cu")
		(at 86.106 -58.7756)
		(property "Reference" "U29"
			(at -3.00863 0.1016 90)
			(unlocked yes)
			(layer "F.SilkS")
			(effects
				(font
					(size 0.7874 0.5842)
					(thickness 0.1524)
				)
			)
		)
		(property "Value" ""
			(at 0 0 0)
			(layer "F.Fab")
			(effects
				(font
					(size 1.27 1.27)
				)
			)
		)
		(property "Device Type" "BNO080_LGA_28-A246-00002-FB,BNA"
			(at 0.040894 5.13842 0)
			(unlocked yes)
			(layer "F.Fab")
			(hide yes)
			(effects
				(font
					(size 0.7874 0.5842)
					(thickness 0.1524)
				)
			)
		)
		(property "User Part Number" "PARTNUM*"
			(at 0.040894 6.33222 0)
			(unlocked yes)
			(layer "Cmts.User")
			(hide yes)
			(effects
				(font
					(size 0.7874 0.5842)
					(thickness 0.1524)
				)
			)
		)
		(duplicate_pad_numbers_are_jumpers no)
		(pad "1" smd rect
			(at 1.562608 -2.249932)
			(size 0.6858 0.254)
			(layers "F.Cu" "F.Mask" "F.Paste")
			(net "Net_782")
		)
		(pad "2" smd rect
			(at 0.750062 -2.312416)
			(size 0.254 0.5842)
			(layers "F.Cu" "F.Mask" "F.Paste")
			(net "SG")
		)
		(pad "3" smd rect
			(at 0.249936 -2.312416)
			(size 0.254 0.5842)
			(layers "F.Cu" "F.Mask" "F.Paste")
			(net "VDD_BNO085")
		)
		(pad "4" smd rect
			(at -0.249936 -2.312416)
			(size 0.254 0.5842)
			(layers "F.Cu" "F.Mask" "F.Paste")
			(net "R_BNO080_BOOT_N")
		)
		(pad "5" smd rect
			(at -0.750062 -2.312416)
			(size 0.254 0.5842)
			(layers "F.Cu" "F.Mask" "F.Paste")
			(net "UNNAMED_9_BNO080LGA28_I29_PS1")
		)
		(pad "6" smd rect
			(at -1.562608 -2.249932)
			(size 0.6858 0.254)
			(layers "F.Cu" "F.Mask" "F.Paste")
			(net "UNNAMED_9_BNO080LGA28_I29_PS0")
		)
		(pad "7" smd rect
			(at -1.562608 -1.75006)
			(size 0.6858 0.254)
			(layers "F.Cu" "F.Mask" "F.Paste")
			(net "Net_781")
		)
		(pad "8" smd rect
			(at -1.562608 -1.249934)
			(size 0.6858 0.254)
			(layers "F.Cu" "F.Mask" "F.Paste")
			(net "Net_780")
		)
		(pad "9" smd rect
			(at -1.562608 -0.750062)
			(size 0.6858 0.254)
			(layers "F.Cu" "F.Mask" "F.Paste")
			(net "UNNAMED_9_BNO080LGA28_I29_CAP")
		)
		(pad "10" smd rect
			(at -1.562608 -0.249936)
			(size 0.6858 0.254)
			(layers "F.Cu" "F.Mask" "F.Paste")
			(net "UNNAMED_9_BNO080LGA28_I29_CLKSE")
		)
		(pad "11" smd rect
			(at -1.562608 0.249936)
			(size 0.6858 0.254)
			(layers "F.Cu" "F.Mask" "F.Paste")
			(net "R_BNO080_RST_N")
		)
		(pad "12" smd rect
			(at -1.562608 0.750062)
			(size 0.6858 0.254)
			(layers "F.Cu" "F.Mask" "F.Paste")
			(net "Net_779")
		)
		(pad "13" smd rect
			(at -1.562608 1.249934)
			(size 0.6858 0.254)
			(layers "F.Cu" "F.Mask" "F.Paste")
			(net "Net_778")
		)
		(pad "14" smd rect
			(at -1.562608 1.75006)
			(size 0.6858 0.254)
			(layers "F.Cu" "F.Mask" "F.Paste")
			(net "R_BNO080_INT_N")
		)
		(pad "15" smd rect
			(at -1.562608 2.249932)
			(size 0.6858 0.254)
			(layers "F.Cu" "F.Mask" "F.Paste")
			(net "R_BNO080_EVN_SCL")
		)
		(pad "16" smd rect
			(at -0.750062 2.312416)
			(size 0.254 0.5842)
			(layers "F.Cu" "F.Mask" "F.Paste")
			(net "R_BNO080_EVN_SDA")
		)
		(pad "17" smd rect
			(at -0.249936 2.312416)
			(size 0.254 0.5842)
			(layers "F.Cu" "F.Mask" "F.Paste")
			(net "BNO080_SA0")
		)
		(pad "18" smd rect
			(at 0.249936 2.312416)
			(size 0.254 0.5842)
			(layers "F.Cu" "F.Mask" "F.Paste")
			(net "UNNAMED_9_BNO080LGA28_I29_HCS")
		)
		(pad "19" smd rect
			(at 0.750062 2.312416)
			(size 0.254 0.5842)
			(layers "F.Cu" "F.Mask" "F.Paste")
			(net "R_BNO080_I2C_SCL")
		)
		(pad "20" smd rect
			(at 1.562608 2.249932)
			(size 0.6858 0.254)
			(layers "F.Cu" "F.Mask" "F.Paste")
			(net "R_BNO080_I2C_SDA")
		)
		(pad "21" smd rect
			(at 1.562608 1.75006)
			(size 0.6858 0.254)
			(layers "F.Cu" "F.Mask" "F.Paste")
			(net "Net_777")
		)
		(pad "22" smd rect
			(at 1.562608 1.249934)
			(size 0.6858 0.254)
			(layers "F.Cu" "F.Mask" "F.Paste")
			(net "Net_776")
		)
		(pad "23" smd rect
			(at 1.562608 0.750062)
			(size 0.6858 0.254)
			(layers "F.Cu" "F.Mask" "F.Paste")
			(net "Net_775")
		)
		(pad "24" smd rect
			(at 1.562608 0.249936)
			(size 0.6858 0.254)
			(layers "F.Cu" "F.Mask" "F.Paste")
			(net "Net_774")
		)
		(pad "25" smd rect
			(at 1.562608 -0.249936)
			(size 0.6858 0.254)
			(layers "F.Cu" "F.Mask" "F.Paste")
			(net "SG")
		)
		(pad "26" smd rect
			(at 1.562608 -0.750062)
			(size 0.6858 0.254)
			(layers "F.Cu" "F.Mask" "F.Paste")
			(net "UNNAMED_9_BNO080LGA28_I29_XOUT3")
		)
		(pad "27" smd rect
			(at 1.562608 -1.249934)
			(size 0.6858 0.254)
			(layers "F.Cu" "F.Mask" "F.Paste")
			(net "UNNAMED_9_CAPACITOR_I17_1")
		)
		(pad "28" smd rect
			(at 1.562608 -1.75006)
			(size 0.6858 0.254)
			(layers "F.Cu" "F.Mask" "F.Paste")
			(net "VDD_BNO085")
		)
	)
)
